# T6G (Grand Teton) — schematic netlist excerpt (pin names and nets, part order shuffled) for the footprints in the layout excerpt that follows; sources: Cadence DE-HDL packaged netlist, KiCad conversion of 04192023_DAF0TMB3IC0_F0TG_MB_C_brd_V02_OCP.brd

PC2229  Q_CAP  0.22UF 16V 10% X7R  pkg 0402  page 152 : A = P12V_SCM_TIMER ; B = GND
R3535  Q_RES  2.2K 5% CHIP  pkg 0402LF  page 250 : A = P3V3_AUX ; B = SMB_SENSOR_E1S_3V3AUX_SCL

(kicad_pcb
	(version 20260206)
	(generator "pcbnew")
	(generator_version "10.0")
	(general
		(thickness 1.6)
		(legacy_teardrops no)
	)
	(paper "A4")
	(title_block
		(title "04192023_DAF0TMB3IC0_F0TG_MB_C_brd_V02_OCP.brd")
		(comment 1 "Grand Teton / footprints 3735-3736 of 8354")
	)
	(layers
		(0 "F.Cu" signal "TOP")
		(4 "In1.Cu" signal "GND")
		(6 "In2.Cu" signal "IN1")
		(8 "In3.Cu" signal "GND1")
		(10 "In4.Cu" signal "IN2")
		(12 "In5.Cu" signal "GND2")
		(14 "In6.Cu" signal "IN3")
		(16 "In7.Cu" signal "GND3")
		(18 "In8.Cu" signal "VCC")
		(20 "In9.Cu" signal "VCC1")
		(22 "In10.Cu" signal "GND4")
		(24 "In11.Cu" signal "IN4")
		(26 "In12.Cu" signal "GND5")
		(28 "In13.Cu" signal "IN5")
		(30 "In14.Cu" signal "GND6")
		(32 "In15.Cu" signal "IN6")
		(34 "In16.Cu" signal "GND7")
		(2 "B.Cu" signal "BOTTOM")
		(9 "F.Adhes" user "F.Adhesive")
		(11 "B.Adhes" user "B.Adhesive")
		(13 "F.Paste" user "Package Geometry/Pastemask Top")
		(15 "B.Paste" user "Package Geometry/Pastemask Bottom")
		(5 "F.SilkS" user "Ref Des/Silkscreen Top")
		(7 "B.SilkS" user "Ref Des/Silkscreen Bottom")
		(1 "F.Mask" user "Board Geometry/Soldermask Top")
		(3 "B.Mask" user "Board Geometry/Soldermask Bottom")
		(17 "Dwgs.User" user "User.Drawings")
		(19 "Cmts.User" user "User.Comments")
		(21 "Eco1.User" user "User.Eco1")
		(23 "Eco2.User" user "User.Eco2")
		(25 "Edge.Cuts" user "Board Geometry/Outline")
		(27 "Margin" user)
		(31 "F.CrtYd" user "Package Geometry/Place Bound Top")
		(29 "B.CrtYd" user "Package Geometry/Place Bound Bottom")
		(35 "F.Fab" user "Ref Des/Assembly Top")
		(33 "B.Fab" user "Ref Des/Assembly Bottom")
	)
	(footprint ""
		(layer "F.Cu")
		(at 179.058062 -32.935672 90)
		(property "Reference" "PC2229"
			(at 0 0 90)
			(layer "F.SilkS")
			(hide yes)
			(effects
				(font
					(size 1.27 1.27)
				)
			)
		)
		(property "Value" ""
			(at 0 0 90)
			(layer "F.Fab")
			(effects
				(font
					(size 1.27 1.27)
				)
			)
		)
		(duplicate_pad_numbers_are_jumpers no)
		(fp_line
			(start 0.7874 -0.4064)
			(end 0.7874 0.4064)
			(stroke
				(width 0.1524)
				(type default)
			)
			(layer "F.SilkS")
		)
		(fp_line
			(start -0.7874 -0.4064)
			(end 0.7874 -0.4064)
			(stroke
				(width 0.1524)
				(type default)
			)
			(layer "F.SilkS")
		)
		(fp_line
			(start 0.7874 0.4064)
			(end -0.7874 0.4064)
			(stroke
				(width 0.1524)
				(type default)
			)
			(layer "F.SilkS")
		)
		(fp_line
			(start -0.7874 0.4064)
			(end -0.7874 -0.4064)
			(stroke
				(width 0.1524)
				(type default)
			)
			(layer "F.SilkS")
		)
		(fp_line
			(start -0.12065 -0.305054)
			(end -0.12065 -0.2794)
			(stroke
				(width 0.1)
				(type default)
			)
			(layer "F.Fab")
		)
		(fp_line
			(start -0.67945 -0.305054)
			(end -0.12065 -0.305054)
			(stroke
				(width 0.1)
				(type default)
			)
			(layer "F.Fab")
		)
		(fp_line
			(start 0.67945 -0.3048)
			(end 0.67945 0.3048)
			(stroke
				(width 0.1)
				(type default)
			)
			(layer "F.Fab")
		)
		(fp_line
			(start 0.12065 -0.3048)
			(end 0.67945 -0.3048)
			(stroke
				(width 0.1)
				(type default)
			)
			(layer "F.Fab")
		)
		(fp_line
			(start 0.12065 -0.2794)
			(end 0.12065 -0.3048)
			(stroke
				(width 0.1)
				(type default)
			)
			(layer "F.Fab")
		)
		(fp_line
			(start -0.12065 -0.2794)
			(end 0.12065 -0.2794)
			(stroke
				(width 0.1)
				(type default)
			)
			(layer "F.Fab")
		)
		(fp_line
			(start 0.120396 0.2794)
			(end -0.12065 0.2794)
			(stroke
				(width 0.1)
				(type default)
			)
			(layer "F.Fab")
		)
		(fp_line
			(start -0.12065 0.2794)
			(end -0.12065 0.3048)
			(stroke
				(width 0.1)
				(type default)
			)
			(layer "F.Fab")
		)
		(fp_line
			(start 0.67945 0.3048)
			(end 0.120396 0.3048)
			(stroke
				(width 0.1)
				(type default)
			)
			(layer "F.Fab")
		)
		(fp_line
			(start 0.120396 0.3048)
			(end 0.120396 0.2794)
			(stroke
				(width 0.1)
				(type default)
			)
			(layer "F.Fab")
		)
		(fp_line
			(start -0.12065 0.3048)
			(end -0.67945 0.3048)
			(stroke
				(width 0.1)
				(type default)
			)
			(layer "F.Fab")
		)
		(fp_line
			(start -0.67945 0.3048)
			(end -0.67945 -0.305054)
			(stroke
				(width 0.1)
				(type default)
			)
			(layer "F.Fab")
		)
		(pad "1" smd circle
			(at -0.40005 0 90)
			(size 0 0)
			(layers "F.Cu" "F.Mask" "F.Paste")
			(net "P12V_SCM_TIMER")
		)
		(pad "2" smd circle
			(at 0.40005 0 90)
			(size 0 0)
			(layers "F.Cu" "F.Mask" "F.Paste")
			(net "GND")
		)
	)
	(footprint ""
		(layer "F.Cu")
		(at 277.352252 -111.91367)
		(property "Reference" "R3535"
			(at 0 0 0)
			(layer "F.SilkS")
			(hide yes)
			(effects
				(font
					(size 1.27 1.27)
				)
			)
		)
		(property "Value" ""
			(at 0 0 0)
			(layer "F.Fab")
			(effects
				(font
					(size 1.27 1.27)
				)
			)
		)
		(duplicate_pad_numbers_are_jumpers no)
		(fp_line
			(start -0.7874 -0.4064)
			(end 0.7874 -0.4064)
			(stroke
				(width 0.1524)
				(type default)
			)
			(layer "F.SilkS")
		)
		(fp_line
			(start -0.7874 0.4064)
			(end -0.7874 -0.4064)
			(stroke
				(width 0.1524)
				(type default)
			)
			(layer "F.SilkS")
		)
		(fp_line
			(start 0.7874 -0.4064)
			(end 0.7874 0.4064)
			(stroke
				(width 0.1524)
				(type default)
			)
			(layer "F.SilkS")
		)
		(fp_line
			(start 0.7874 0.4064)
			(end -0.7874 0.4064)
			(stroke
				(width 0.1524)
				(type default)
			)
			(layer "F.SilkS")
		)
		(fp_line
			(start -0.67945 -0.305054)
			(end -0.12065 -0.305054)
			(stroke
				(width 0.1)
				(type default)
			)
			(layer "F.Fab")
		)
		(fp_line
			(start -0.67945 0.3048)
			(end -0.67945 -0.305054)
			(stroke
				(width 0.1)
				(type default)
			)
			(layer "F.Fab")
		)
		(fp_line
			(start -0.12065 -0.305054)
			(end -0.12065 -0.2794)
			(stroke
				(width 0.1)
				(type default)
			)
			(layer "F.Fab")
		)
		(fp_line
			(start -0.12065 -0.2794)
			(end 0.12065 -0.2794)
			(stroke
				(width 0.1)
				(type default)
			)
			(layer "F.Fab")
		)
		(fp_line
			(start -0.12065 0.2794)
			(end -0.12065 0.3048)
			(stroke
				(width 0.1)
				(type default)
			)
			(layer "F.Fab")
		)
		(fp_line
			(start -0.12065 0.3048)
			(end -0.67945 0.3048)
			(stroke
				(width 0.1)
				(type default)
			)
			(layer "F.Fab")
		)
		(fp_line
			(start 0.120396 0.2794)
			(end -0.12065 0.2794)
			(stroke
				(width 0.1)
				(type default)
			)
			(layer "F.Fab")
		)
		(fp_line
			(start 0.120396 0.3048)
			(end 0.120396 0.2794)
			(stroke
				(width 0.1)
				(type default)
			)
			(layer "F.Fab")
		)
		(fp_line
			(start 0.12065 -0.3048)
			(end 0.67945 -0.3048)
			(stroke
				(width 0.1)
				(type default)
			)
			(layer "F.Fab")
		)
		(fp_line
			(start 0.12065 -0.2794)
			(end 0.12065 -0.3048)
			(stroke
				(width 0.1)
				(type default)
			)
			(layer "F.Fab")
		)
		(fp_line
			(start 0.67945 -0.3048)
			(end 0.67945 0.3048)
			(stroke
				(width 0.1)
				(type default)
			)
			(layer "F.Fab")
		)
		(fp_line
			(start 0.67945 0.3048)
			(end 0.120396 0.3048)
			(stroke
				(width 0.1)
				(type default)
			)
			(layer "F.Fab")
		)
		(pad "1" smd circle
			(at -0.40005 0)
			(size 0 0)
			(layers "F.Cu" "F.Mask" "F.Paste")
			(net "P3V3_AUX")
		)
		(pad "2" smd circle
			(at 0.40005 0)
			(size 0 0)
			(layers "F.Cu" "F.Mask" "F.Paste")
			(net "SMB_SENSOR_E1S_3V3AUX_SCL")
		)
	)
)
